FILE_TYPE = CONNECTIVITY;
{Allegro Design Entry HDL 16.6-p007 (v16-6-112F) 10/10/2012}
"PAGE_NUMBER" = 127;
0"NC";
1"GND\g";
2"P1V05_PCH_STBY\g";
3"GND\g";
4"P1V05_PCH_STBY\g";
5"GND\g";
6"GND\g";
7"GND\g";
8"P1V05_PCH_STBY_VCCA_XTAL\g"VOLTAGE"+1.05V";
9"P1V05_PCH_STBY_WM20_PLL\g"VOLTAGE"1.05V";
10"P1V05_PCH_STBY\g";
11"P1V05_PCH_STBY_WM26_PLL\g"VOLTAGE"1.05V";
12"GND\g";
13"P1V05_PCH_STBY_ISCLK_PLL\g"VOLTAGE"1.05V";
14"P1V05_PCH_STBY\g";
15"GND\g";
16"GND\g";
17"GND\g";
18"GND\g";
19"P1V05_PCH_STBY_KR_PLL\g"VOLTAGE"1.05V";
20"GND\g";
21"P1V05_PCH_STBY\g";
22"P1V05_PCH_STBY\g";
23"P1V05_PCH_STBY\g";
24"P1V05_PCH_STBY_VCCA_PLL0\g"VOLTAGE"+1.05V";
25"P1V05_PCH_STBY_VCCA_PLL1\g"VOLTAGE"+1.05V";
26"GND\g";
27"GND\g";
28"GND\g";
%"GND"
"1","(-3425,-2600)","0","mstr_symbols","I14";
;
BODY_TYPE"PLUMBING"
SIZE"1B"
CDS_LIB"mstr_symbols"
HDL_POWER"GND"
VOLTAGE"0.0V";
"A\NAC"1;
%"P1V05_PCH_STBY"
"1","(-4275,-1700)","0","mstr_symbols","I16";
;
BODY_TYPE"PLUMBING"
CDS_LIB"mstr_symbols"
HDL_POWER"P1V05_PCH_STBY"
VOLTAGE"1.05V";
"G\NAC"2;
%"FERRITE"
"1","(-4025,-2050)","0","mstr_discrete","I17";
;
CDS_SEC"1"
MATERIAL"FB"
PACK_TYPE"SM"
VALUE"120"
PART_NUMBER"693286-027"
LOCATION"FB3M2"
CDS_LOCATION"FB3M2"
SEC"1"
SEC_TYPE"SM"
CDS_LIB"mstr_discrete"
BOM_COST"SB"
ROOM"SB_FILTER_PLL1";
"A"
$PN"1"2;
"B"
$PN"2"24;
%"CAP_A"
"1","(-4275,-2250)","2","dev_discrete","I18";
;
VOLTAGE"6.3V"
PACK_TYPE"0402V"
TOLERANCE"10%"
VALUE"1.0UF"
PART_NUMBER"D97712-004"
LOCATION"C3M22"
MATERIAL"X6S"
SEC"1"
SEC_TYPE"0402V"
CDS_SEC"1"
CDS_LIB"dev_discrete"
BOM_COST"SB"
CDS_LOCATION"C3M22"
ROOM"SB_FILTER_PLL1";
"B"
$PN"2"1;
"A"
$PN"1"2;
%"GND"
"1","(-3400,-3900)","0","mstr_symbols","I23";
;
BODY_TYPE"PLUMBING"
SIZE"1B"
CDS_LIB"mstr_symbols"
HDL_POWER"GND"
VOLTAGE"0.0V";
"A\NAC"3;
%"P1V05_PCH_STBY"
"1","(-4250,-3000)","0","mstr_symbols","I25";
;
BODY_TYPE"PLUMBING"
CDS_LIB"mstr_symbols"
HDL_POWER"P1V05_PCH_STBY"
VOLTAGE"1.05V";
"G\NAC"4;
%"FERRITE"
"1","(-4000,-3350)","0","mstr_discrete","I26";
;
CDS_SEC"1"
MATERIAL"FB"
PACK_TYPE"SM"
VALUE"120"
PART_NUMBER"693286-027"
LOCATION"FB3M3"
CDS_LOCATION"FB3M3"
SEC"1"
SEC_TYPE"SM"
BOM_COST"SB"
CDS_LIB"mstr_discrete"
ROOM"SB_FILTER_XTAL";
"A"
$PN"1"4;
"B"
$PN"2"8;
%"CAP_A"
"1","(-4250,-3550)","2","dev_discrete","I27";
;
MATERIAL"X6S"
VOLTAGE"6.3V"
PACK_TYPE"0402V"
TOLERANCE"10%"
VALUE"1.0UF"
PART_NUMBER"D97712-004"
LOCATION"C3M30"
SEC"1"
SEC_TYPE"0402V"
CDS_SEC"1"
CDS_LIB"dev_discrete"
BOM_COST"SB"
CDS_LOCATION"C3M30"
ROOM"SB_FILTER_XTAL";
"B"
$PN"2"3;
"A"
$PN"1"4;
%"GND"
"1","(-2575,-1325)","0","mstr_symbols","I32";
;
BODY_TYPE"PLUMBING"
SIZE"1B"
CDS_LIB"mstr_symbols"
HDL_POWER"GND"
VOLTAGE"0.0V";
"A\NAC"5;
%"GND"
"1","(-2575,-2600)","0","mstr_symbols","I34";
;
BODY_TYPE"PLUMBING"
CDS_LIB"mstr_symbols"
SIZE"1B"
HDL_POWER"GND"
VOLTAGE"0.0V";
"A\NAC"6;
%"GND"
"1","(-2550,-3850)","0","mstr_symbols","I36";
;
BODY_TYPE"PLUMBING"
SIZE"1B"
CDS_LIB"mstr_symbols"
HDL_POWER"GND"
VOLTAGE"0.0V";
"A\NAC"7;
%"P1V05_PCH_STBY_VCCA_XTAL"
"1","(-2550,-2975)","0","mstr_symbols","I39";
;
BODY_TYPE"PLUMBING"
CDS_LIB"mstr_symbols"
BOM_COST"SB"
ROOM"SB_DECOUPLING"
HDL_POWER"P1V05_PCH_STBY_VCCA_XTAL"
VOLTAGE"1.05V";
"G\NAC"8;
%"P1V05_PCH_STBY_WM20_PLL"
"1","(1850,-750)","0","mstr_symbols","I40";
;
BOM_COST"SB"
CDS_LIB"mstr_symbols"
BODY_TYPE"PLUMBING"
ROOM"SB_DECOUPLING"
HDL_POWER"P1V05_PCH_STBY_WM20_PLL"
VOLTAGE"1.05V";
"G\NAC"9;
%"CAP"
"1","(1850,-1375)","0","mstr_discrete","I43";
;
CDS_SEC"1"
MATERIAL"X6S"
VOLTAGE"4V"
PACK_TYPE"0603LF"
TOLERANCE"20%"
VALUE"10UF"
PART_NUMBER"E15431-001"
LOCATION"C2M5"
CDS_LOCATION"C2M5"
SEC"1"
SEC_TYPE"0603LF"
BOM_COST"SB"
CDS_LIB"mstr_discrete"
ROOM"SB_FILTER_VM20";
"A"
$PN"1"9;
"B"
$PN"2"12;
%"CAP_A"
"1","(1400,-1375)","0","dev_discrete","I44";
;
MATERIAL"X6S"
VOLTAGE"6.3V"
PACK_TYPE"0402V"
TOLERANCE"10%"
VALUE"1.0UF"
PART_NUMBER"D97712-004"
LOCATION"C2M7"
SEC"1"
SEC_TYPE"0402V"
CDS_SEC"1"
CDS_LIB"dev_discrete"
BOM_COST"SB"
CDS_LOCATION"C2M7"
ROOM"SB_FILTER_VM20";
"B"
$PN"2"12;
"A"
$PN"1"9;
%"P1V05_PCH_STBY"
"1","(950,-825)","0","mstr_symbols","I45";
;
BODY_TYPE"PLUMBING"
CDS_LIB"mstr_symbols"
HDL_POWER"P1V05_PCH_STBY"
VOLTAGE"1.05V";
"G\NAC"10;
%"FERRITE"
"1","(1150,-1175)","0","mstr_discrete","I46";
;
CDS_SEC"1"
MATERIAL"FB"
PACK_TYPE"SM"
VALUE"120"
LOCATION"FB2M1"
PART_NUMBER"693286-027"
CDS_LOCATION"FB2M1"
SEC"1"
CDS_LIB"mstr_discrete"
SEC_TYPE"SM"
BOM_COST"SB"
ROOM"SB_FILTER_VM20";
"A"
$PN"1"10;
"B"
$PN"2"9;
%"P1V05_PCH_STBY_WM26_PLL"
"1","(-500,-800)","0","mstr_symbols","I47";
;
BODY_TYPE"PLUMBING"
CDS_LIB"mstr_symbols"
BOM_COST"SB"
ROOM"SB_DECOUPLING"
HDL_POWER"P1V05_PCH_STBY_WM26_PLL"
VOLTAGE"1.05V";
"G\NAC"11;
%"CAP"
"1","(-500,-1400)","0","mstr_discrete","I49";
;
CDS_SEC"1"
MATERIAL"X6S"
VOLTAGE"4V"
VALUE"10UF"
LOCATION"C2M10"
TOLERANCE"20%"
PACK_TYPE"0603LF"
PART_NUMBER"E15431-001"
CDS_LOCATION"C2M10"
SEC"1"
CDS_LIB"mstr_discrete"
BOM_COST"SB"
SEC_TYPE"0603LF"
ROOM"SB_FILTER_VM26";
"A"
$PN"1"11;
"B"
$PN"2"18;
%"CAP_A"
"1","(-1000,-1400)","0","dev_discrete","I50";
;
MATERIAL"X6S"
VOLTAGE"6.3V"
PACK_TYPE"0402V"
TOLERANCE"10%"
VALUE"1.0UF"
PART_NUMBER"D97712-004"
LOCATION"C2M9"
SEC"1"
SEC_TYPE"0402V"
CDS_SEC"1"
CDS_LIB"dev_discrete"
BOM_COST"SB"
CDS_LOCATION"C2M9"
ROOM"SB_FILTER_VM26";
"B"
$PN"2"18;
"A"
$PN"1"11;
%"GND"
"1","(1400,-1725)","0","mstr_symbols","I51";
;
BODY_TYPE"PLUMBING"
SIZE"1B"
CDS_LIB"mstr_symbols"
HDL_POWER"GND"
VOLTAGE"0.0V";
"A\NAC"12;
%"P1V05_PCH_STBY_ISCLK_PLL"
"1","(1700,-2700)","0","mstr_symbols","I52";
;
BODY_TYPE"PLUMBING"
CDS_LIB"mstr_symbols"
BOM_COST"SB"
ROOM"SB_DECOUPLING"
HDL_POWER"P1V05_PCH_STBY_ISCLK_PLL"
VOLTAGE"1.05V";
"G\NAC"13;
%"P1V05_PCH_STBY"
"1","(950,-2725)","0","mstr_symbols","I55";
;
BODY_TYPE"PLUMBING"
CDS_LIB"mstr_symbols"
HDL_POWER"P1V05_PCH_STBY"
VOLTAGE"1.05V";
"G\NAC"14;
%"FERRITE"
"1","(1150,-3075)","0","mstr_discrete","I56";
;
CDS_SEC"1"
MATERIAL"FB"
PACK_TYPE"SM"
VALUE"120"
PART_NUMBER"693286-027"
LOCATION"FB3M4"
CDS_LOCATION"FB3M4"
SEC"1"
CDS_LIB"mstr_discrete"
SEC_TYPE"SM"
BOM_COST"SB"
ROOM"SB_FILTER_ISCLK";
"A"
$PN"1"14;
"B"
$PN"2"13;
%"CAP_A"
"1","(950,-3275)","2","dev_discrete","I57";
;
MATERIAL"X6S"
VOLTAGE"6.3V"
PACK_TYPE"0402V"
TOLERANCE"10%"
VALUE"1.0UF"
PART_NUMBER"D97712-004"
LOCATION"C3M31"
SEC"1"
SEC_TYPE"0402V"
CDS_SEC"1"
CDS_LIB"dev_discrete"
BOM_COST"SB"
CDS_LOCATION"C3M31"
ROOM"SB_FILTER_ISCLK";
"B"
$PN"2"16;
"A"
$PN"1"14;
%"GND"
"1","(1700,-3625)","0","mstr_symbols","I58";
;
BODY_TYPE"PLUMBING"
CDS_LIB"mstr_symbols"
SIZE"1B"
HDL_POWER"GND"
VOLTAGE"0.0V";
"A\NAC"15;
%"GND"
"1","(950,-3675)","0","mstr_symbols","I59";
;
BODY_TYPE"PLUMBING"
SIZE"1B"
CDS_LIB"mstr_symbols"
HDL_POWER"GND"
VOLTAGE"0.0V";
"A\NAC"16;
%"GND"
"1","(-3450,-1400)","0","mstr_symbols","I6";
;
BODY_TYPE"PLUMBING"
CDS_LIB"mstr_symbols"
SIZE"1B"
HDL_POWER"GND"
VOLTAGE"0.0V";
"A\NAC"17;
%"GND"
"1","(-1000,-1750)","0","mstr_symbols","I61";
;
BODY_TYPE"PLUMBING"
CDS_LIB"mstr_symbols"
SIZE"1B"
HDL_POWER"GND"
VOLTAGE"0.0V";
"A\NAC"18;
%"P1V05_PCH_STBY_KR_PLL"
"1","(-500,-2650)","0","mstr_symbols","I62";
;
BOM_COST"SB"
CDS_LIB"mstr_symbols"
BODY_TYPE"PLUMBING"
ROOM"SB_DECOUPLING"
HDL_POWER"P1V05_PCH_STBY_KR_PLL"
VOLTAGE"1.05V";
"G\NAC"19;
%"CAP"
"1","(-500,-3300)","0","mstr_discrete","I64";
;
CDS_SEC"1"
MATERIAL"X6S"
VOLTAGE"4V"
TOLERANCE"20%"
VALUE"10UF"
PART_NUMBER"E15431-001"
LOCATION"C2N6"
PACK_TYPE"0603LF"
CDS_LOCATION"C2N6"
SEC"1"
CDS_LIB"mstr_discrete"
BOM_COST"SB"
SEC_TYPE"0603LF"
ROOM"SB_FILTER_KR_PLL";
"A"
$PN"1"19;
"B"
$PN"2"20;
%"CAP_A"
"1","(-1000,-3300)","0","dev_discrete","I65";
;
MATERIAL"X6S"
VOLTAGE"6.3V"
PACK_TYPE"0402V"
TOLERANCE"10%"
VALUE"1.0UF"
PART_NUMBER"D97712-004"
LOCATION"C2N5"
SEC"1"
SEC_TYPE"0402V"
CDS_SEC"1"
CDS_LIB"dev_discrete"
BOM_COST"SB"
CDS_LOCATION"C2N5"
ROOM"SB_FILTER_KR_PLL";
"B"
$PN"2"20;
"A"
$PN"1"19;
%"GND"
"1","(-500,-3650)","0","mstr_symbols","I66";
;
BODY_TYPE"PLUMBING"
SIZE"1B"
CDS_LIB"mstr_symbols"
HDL_POWER"GND"
VOLTAGE"0.0V";
"A\NAC"20;
%"P1V05_PCH_STBY"
"1","(-1450,-850)","0","mstr_symbols","I68";
;
BODY_TYPE"PLUMBING"
CDS_LIB"mstr_symbols"
HDL_POWER"P1V05_PCH_STBY"
VOLTAGE"1.05V";
"G\NAC"21;
%"FERRITE"
"1","(-1225,-1200)","0","mstr_discrete","I69";
;
CDS_SEC"1"
MATERIAL"FB"
PACK_TYPE"SM"
VALUE"120"
PART_NUMBER"693286-027"
LOCATION"FB2M2"
CDS_LOCATION"FB2M2"
SEC"1"
CDS_LIB"mstr_discrete"
BOM_COST"SB"
SEC_TYPE"SM"
ROOM"SB_FILTER_VM26";
"A"
$PN"1"21;
"B"
$PN"2"11;
%"P1V05_PCH_STBY"
"1","(-4300,-500)","0","mstr_symbols","I7";
;
BODY_TYPE"PLUMBING"
CDS_LIB"mstr_symbols"
HDL_POWER"P1V05_PCH_STBY"
VOLTAGE"1.05V";
"G\NAC"22;
%"P1V05_PCH_STBY"
"1","(-1450,-2725)","0","mstr_symbols","I70";
;
BODY_TYPE"PLUMBING"
CDS_LIB"mstr_symbols"
HDL_POWER"P1V05_PCH_STBY"
VOLTAGE"1.05V";
"G\NAC"23;
%"INDUCTOR"
"1","(-1250,-3100)","0","mstr_discrete","I71";
;
CDS_SEC"1"
MATERIAL"IND"
PACK_TYPE"SMT"
PART_NUMBER"721891-082"
LOCATION"L2M1"
VALUE"0.022UH"
CDS_LOCATION"L2M1"
SEC"1"
SEC_TYPE"SMT"
CDS_LIB"mstr_discrete"
BOM_COST"SB"
ROOM"SB_FILTER_KR_PLL";
"INA\NAC"
$PN"1"23;
"INB\NAC"
$PN"2"19;
%"P1V05_PCH_STBY_VCCA_PLL0"
"1","(-2575,-1675)","0","mstr_symbols","I72";
;
BODY_TYPE"PLUMBING"
CDS_LIB"mstr_symbols"
BOM_COST"SB"
ROOM"SB_DECOUPLING"
HDL_POWER"P1V05_PCH_STBY_VCCA_PLL0"
VOLTAGE"1.05V";
"G\NAC"24;
%"P1V05_PCH_STBY_VCCA_PLL1"
"1","(-2575,-475)","0","mstr_symbols","I73";
;
BODY_TYPE"PLUMBING"
CDS_LIB"mstr_symbols"
BOM_COST"SB"
ROOM"SB_DECOUPLING"
HDL_POWER"P1V05_PCH_STBY_VCCA_PLL1"
VOLTAGE"1.05V";
"G\NAC"25;
%"CAP_A"
"1","(-1450,-1400)","2","dev_discrete","I74";
;
MATERIAL"X6S"
PACK_TYPE"0402V"
VALUE"1.0UF"
PART_NUMBER"D97712-004"
LOCATION"C2M8"
VOLTAGE"6.3V"
TOLERANCE"10%"
SEC"1"
SEC_TYPE"0402V"
CDS_SEC"1"
CDS_LIB"dev_discrete"
BOM_COST"SB"
CDS_LOCATION"C2M8"
ROOM"SB_FILTER_VM26";
"B"
$PN"2"26;
"A"
$PN"1"21;
%"GND"
"1","(-1450,-1750)","0","mstr_symbols","I75";
;
BODY_TYPE"PLUMBING"
SIZE"1B"
CDS_LIB"mstr_symbols"
HDL_POWER"GND"
VOLTAGE"0.0V";
"A\NAC"26;
%"CAP_A"
"1","(950,-1375)","2","dev_discrete","I76";
;
MATERIAL"X6S"
VOLTAGE"6.3V"
PACK_TYPE"0402V"
TOLERANCE"10%"
VALUE"1.0UF"
PART_NUMBER"D97712-004"
LOCATION"C2M6"
SEC"1"
SEC_TYPE"0402V"
CDS_SEC"1"
CDS_LIB"dev_discrete"
BOM_COST"SB"
CDS_LOCATION"C2M6"
ROOM"SB_FILTER_VM20";
"B"
$PN"2"27;
"A"
$PN"1"10;
%"GND"
"1","(950,-1725)","0","mstr_symbols","I77";
;
BODY_TYPE"PLUMBING"
CDS_LIB"mstr_symbols"
SIZE"1B"
HDL_POWER"GND"
VOLTAGE"0.0V";
"A\NAC"27;
%"CAP_A"
"1","(-1450,-3300)","2","dev_discrete","I78";
;
VOLTAGE"6.3V"
PACK_TYPE"0402V"
TOLERANCE"10%"
VALUE"1.0UF"
PART_NUMBER"D97712-004"
LOCATION"C2M25"
MATERIAL"X6S"
SEC"1"
SEC_TYPE"0402V"
CDS_SEC"1"
CDS_LIB"dev_discrete"
BOM_COST"SB"
ROOM"SB_FILTER_KR_PLL"
CDS_LOCATION"C2M25";
"B"
$PN"2"28;
"A"
$PN"1"23;
%"GND"
"1","(-1450,-3625)","0","mstr_symbols","I79";
;
BODY_TYPE"PLUMBING"
SIZE"1B"
CDS_LIB"mstr_symbols"
HDL_POWER"GND"
VOLTAGE"0.0V";
"A\NAC"28;
%"FERRITE"
"1","(-4050,-850)","0","mstr_discrete","I8";
;
CDS_SEC"1"
MATERIAL"FB"
PACK_TYPE"SM"
PART_NUMBER"693286-027"
LOCATION"FB3M1"
VALUE"120"
CDS_LOCATION"FB3M1"
SEC"1"
SEC_TYPE"SM"
BOM_COST"SB"
CDS_LIB"mstr_discrete"
ROOM"SB_FILTER_PLL0";
"A"
$PN"1"22;
"B"
$PN"2"25;
%"CAP_A"
"1","(1400,-3275)","0","dev_discrete","I80";
;
MATERIAL"X6S"
VOLTAGE"6.3V"
PACK_TYPE"0402V"
TOLERANCE"10%"
VALUE"1.0UF"
PART_NUMBER"D97712-004"
LOCATION"C3M29"
CDS_LOCATION"C3M29"
BOM_COST"SB"
CDS_LIB"dev_discrete"
CDS_SEC"1"
SEC_TYPE"0402V"
SEC"1"
ROOM"SB_FILTER_ISCLK";
"B"
$PN"2"16;
"A"
$PN"1"13;
%"CAP"
"1","(1700,-3275)","0","mstr_discrete","I81";
;
MATERIAL"X6S"
VOLTAGE"4V"
PACK_TYPE"0603LF"
TOLERANCE"20%"
VALUE"10UF"
PART_NUMBER"E15431-001"
LOCATION"C3M24"
CDS_LOCATION"C3M24"
SEC"1"
CDS_LIB"mstr_discrete"
SEC_TYPE"0603LF"
BOM_COST"SB"
CDS_SEC"1"
ROOM"SB_FILTER_ISCLK";
"A"
$PN"1"13;
"B"
$PN"2"15;
%"CAP"
"1","(-2550,-3600)","0","mstr_discrete","I82";
;
MATERIAL"X6S"
VOLTAGE"4V"
PACK_TYPE"0603LF"
TOLERANCE"20%"
VALUE"10UF"
PART_NUMBER"E15431-001"
LOCATION"C3M23"
CDS_LOCATION"C3M23"
SEC"1"
SEC_TYPE"0603LF"
CDS_LIB"mstr_discrete"
BOM_COST"SB"
CDS_SEC"1"
ROOM"SB_FILTER_XTAL";
"A"
$PN"1"8;
"B"
$PN"2"7;
%"CAP_A"
"1","(-3400,-3550)","0","dev_discrete","I83";
;
MATERIAL"X6S"
VOLTAGE"6.3V"
PACK_TYPE"0402V"
TOLERANCE"10%"
VALUE"1.0UF"
PART_NUMBER"D97712-004"
LOCATION"C3M27"
SEC"1"
SEC_TYPE"0402V"
CDS_SEC"1"
CDS_LIB"dev_discrete"
BOM_COST"SB"
CDS_LOCATION"C3M27"
ROOM"SB_FILTER_XTAL";
"B"
$PN"2"3;
"A"
$PN"1"8;
%"CAP_A"
"1","(-3425,-2250)","0","dev_discrete","I84";
;
VOLTAGE"6.3V"
PACK_TYPE"0402V"
TOLERANCE"10%"
VALUE"1.0UF"
PART_NUMBER"D97712-004"
LOCATION"C3M20"
MATERIAL"X6S"
CDS_LOCATION"C3M20"
BOM_COST"SB"
CDS_LIB"dev_discrete"
CDS_SEC"1"
SEC_TYPE"0402V"
SEC"1"
ROOM"SB_FILTER_PLL1";
"B"
$PN"2"1;
"A"
$PN"1"24;
%"CAP"
"1","(-2575,-2325)","0","mstr_discrete","I85";
;
MATERIAL"X6S"
VOLTAGE"4V"
PACK_TYPE"0603LF"
TOLERANCE"20%"
VALUE"10UF"
PART_NUMBER"E15431-001"
LOCATION"C3M18"
CDS_LOCATION"C3M18"
SEC"1"
SEC_TYPE"0603LF"
BOM_COST"SB"
CDS_LIB"mstr_discrete"
CDS_SEC"1"
ROOM"SB_FILTER_PLL1";
"A"
$PN"1"24;
"B"
$PN"2"6;
%"CAP"
"1","(-2575,-1075)","0","mstr_discrete","I86";
;
MATERIAL"X6S"
VOLTAGE"4V"
PACK_TYPE"0603LF"
TOLERANCE"20%"
VALUE"10UF"
PART_NUMBER"E15431-001"
LOCATION"C3M17"
CDS_SEC"1"
BOM_COST"SB"
CDS_LIB"mstr_discrete"
SEC_TYPE"0603LF"
SEC"1"
CDS_LOCATION"C3M17"
ROOM"SB_FILTER_PLL0";
"A"
$PN"1"25;
"B"
$PN"2"5;
%"CAP_A"
"1","(-3450,-1050)","0","dev_discrete","I87";
;
MATERIAL"X6S"
VOLTAGE"6.3V"
PACK_TYPE"0402V"
TOLERANCE"10%"
PART_NUMBER"D97712-004"
LOCATION"C3M19"
VALUE"1.0UF"
CDS_LOCATION"C3M19"
BOM_COST"SB"
CDS_LIB"dev_discrete"
CDS_SEC"1"
SEC_TYPE"0402V"
SEC"1"
ROOM"SB_FILTER_PLL0";
"B"
$PN"2"17;
"A"
$PN"1"25;
%"CAP_A"
"1","(-4300,-1050)","2","dev_discrete","I9";
;
MATERIAL"X6S"
VOLTAGE"6.3V"
PACK_TYPE"0402V"
TOLERANCE"10%"
VALUE"1.0UF"
PART_NUMBER"D97712-004"
LOCATION"C3M21"
SEC"1"
SEC_TYPE"0402V"
CDS_SEC"1"
CDS_LIB"dev_discrete"
BOM_COST"SB"
CDS_LOCATION"C3M21"
ROOM"SB_FILTER_PLL0";
"B"
$PN"2"17;
"A"
$PN"1"22;
END.
